(kicad_pcb
	(version 20260206)
	(generator "pcbnew")
	(generator_version "10.0")
	(general
		(thickness 1.6)
		(legacy_teardrops no)
	)
	(paper "A4")
	(title_block
		(title "dpb — 14545-sa.0730WZS0815.brd")
		(comment 1 "Honey Badger (Wiwynn) / footprints 584-589 of 1066")
	)
	(layers
		(0 "F.Cu" signal "TOP")
		(4 "In1.Cu" signal "L2GND")
		(6 "In2.Cu" signal "L3")
		(8 "In3.Cu" signal "L4VCC")
		(10 "In4.Cu" signal "L5VCC")
		(12 "In5.Cu" signal "L6")
		(14 "In6.Cu" signal "L7GND")
		(2 "B.Cu" signal "BOTTOM")
		(9 "F.Adhes" user "F.Adhesive")
		(11 "B.Adhes" user "B.Adhesive")
		(13 "F.Paste" user "Package Geometry/Pastemask Top")
		(15 "B.Paste" user "Package Geometry/Pastemask Bottom")
		(5 "F.SilkS" user "Ref Des/Silkscreen Top")
		(7 "B.SilkS" user "Ref Des/Silkscreen Bottom")
		(1 "F.Mask" user "Board Geometry/Soldermask Top")
		(3 "B.Mask" user "Board Geometry/Soldermask Bottom")
		(17 "Dwgs.User" user "User.Drawings")
		(19 "Cmts.User" user "User.Comments")
		(21 "Eco1.User" user "User.Eco1")
		(23 "Eco2.User" user "User.Eco2")
		(25 "Edge.Cuts" user "Board Geometry/Outline")
		(27 "Margin" user)
		(31 "F.CrtYd" user "Package Geometry/Place Bound Top")
		(29 "B.CrtYd" user "Package Geometry/Place Bound Bottom")
		(35 "F.Fab" user "Ref Des/Assembly Top")
		(33 "B.Fab" user "Ref Des/Assembly Bottom")
	)
	(footprint ""
		(layer "F.Cu")
		(at 46.735746 -111.1377 -90)
		(property "Reference" "U41"
			(at 0 0 270)
			(layer "F.SilkS")
			(hide yes)
			(effects
				(font
					(size 1.27 1.27)
				)
			)
		)
		(property "Value" "P2003EVG-GP"
			(at 0 -11.1252 270)
			(unlocked yes)
			(layer "F.Fab")
			(hide yes)
			(effects
				(font
					(size 1.016 1.016)
					(thickness 0.1524)
				)
			)
		)
		(property "Device Type" "SOIC8H79"
			(at 0 -12.6492 270)
			(unlocked yes)
			(layer "F.Fab")
			(hide yes)
			(effects
				(font
					(size 1.016 1.016)
					(thickness 0.1524)
				)
			)
		)
		(duplicate_pad_numbers_are_jumpers no)
		(fp_line
			(start -2.6162 3.429)
			(end -2.6162 1.4732)
			(stroke
				(width 0.4064)
				(type default)
			)
			(layer "F.SilkS")
		)
		(fp_line
			(start -2.7432 1.4224)
			(end 2.1336 1.4224)
			(stroke
				(width 0.1524)
				(type default)
			)
			(layer "F.SilkS")
		)
		(fp_line
			(start 2.1336 1.4224)
			(end 2.1336 -1.4224)
			(stroke
				(width 0.1524)
				(type default)
			)
			(layer "F.SilkS")
		)
		(fp_line
			(start -2.2352 0)
			(end -2.7432 0.508)
			(stroke
				(width 0.1524)
				(type default)
			)
			(layer "F.SilkS")
		)
		(fp_line
			(start -2.7432 -0.508)
			(end -2.2352 0)
			(stroke
				(width 0.1524)
				(type default)
			)
			(layer "F.SilkS")
		)
		(fp_line
			(start -2.7432 -1.4224)
			(end -2.7432 1.4224)
			(stroke
				(width 0.1524)
				(type default)
			)
			(layer "F.SilkS")
		)
		(fp_line
			(start 2.1336 -1.4224)
			(end -2.7432 -1.4224)
			(stroke
				(width 0.1524)
				(type default)
			)
			(layer "F.SilkS")
		)
		(fp_poly
			(pts
				(xy 2.2098 -1.4224) (xy 2.2098 1.4224) (xy -2.2225 1.4224) (xy -2.2225 -1.4224)
			)
			(stroke
				(width 0)
				(type default)
			)
			(fill yes)
			(layer "F.SilkS")
		)
		(fp_rect
			(start -2.4511 2.9972)
			(end 2.4511 -2.9972)
			(stroke
				(width 0)
				(type default)
			)
			(fill no)
			(layer "F.CrtYd")
		)
		(fp_poly
			(pts
				(xy -2.8194 3.6322) (xy -2.8194 -3.6322) (xy 2.8194 -3.6322) (xy 2.8194 -2.2987) (xy 2.4511 -2.2987)
				(xy 2.4511 -2.9972) (xy -2.4511 -2.9972) (xy -2.4511 2.9972) (xy 2.4511 2.9972) (xy 2.4511 -2.286)
				(xy 2.8194 -2.286) (xy 2.8194 3.6322)
			)
			(stroke
				(width 0)
				(type default)
			)
			(fill no)
			(layer "F.CrtYd")
		)
		(fp_rect
			(start -2.8194 3.6322)
			(end 2.8194 -3.6322)
			(stroke
				(width 0)
				(type default)
			)
			(fill no)
			(layer "F.Fab")
		)
		(pad "1" smd rect
			(at -1.905 2.54 270)
			(size 0.635 1.651)
			(layers "F.Cu" "F.Mask" "F.Paste")
			(net "P12V")
		)
		(pad "2" smd rect
			(at -0.635 2.54 270)
			(size 0.635 1.651)
			(layers "F.Cu" "F.Mask" "F.Paste")
			(net "P12V")
		)
		(pad "3" smd rect
			(at 0.635 2.54 270)
			(size 0.635 1.651)
			(layers "F.Cu" "F.Mask" "F.Paste")
			(net "P12V")
		)
		(pad "4" smd rect
			(at 1.905 2.54 270)
			(size 0.635 1.651)
			(layers "F.Cu" "F.Mask" "F.Paste")
			(net "SW_HDD13_N")
		)
		(pad "5" smd rect
			(at 1.905 -2.54 270)
			(size 0.635 1.651)
			(layers "F.Cu" "F.Mask" "F.Paste")
			(net "P12V_HDD13")
		)
		(pad "6" smd rect
			(at 0.635 -2.54 270)
			(size 0.635 1.651)
			(layers "F.Cu" "F.Mask" "F.Paste")
			(net "P12V_HDD13")
		)
		(pad "7" smd rect
			(at -0.635 -2.54 270)
			(size 0.635 1.651)
			(layers "F.Cu" "F.Mask" "F.Paste")
			(net "P12V_HDD13")
		)
		(pad "8" smd rect
			(at -1.905 -2.54 270)
			(size 0.635 1.651)
			(layers "F.Cu" "F.Mask" "F.Paste")
			(net "P12V_HDD13")
		)
	)
	(footprint ""
		(layer "F.Cu")
		(at 32.9184 -337.947)
		(property "Reference" "Q69"
			(at 0 0 0)
			(layer "F.SilkS")
			(hide yes)
			(effects
				(font
					(size 1.27 1.27)
				)
			)
		)
		(property "Value" "2N7002-11-GP"
			(at 0.127 -8.9662 0)
			(unlocked yes)
			(layer "F.Fab")
			(hide yes)
			(effects
				(font
					(size 1.016 1.016)
					(thickness 0.1524)
				)
			)
		)
		(property "Device Type" "SOT23DGS2D4H44"
			(at 0.127 -10.4902 0)
			(unlocked yes)
			(layer "F.Fab")
			(hide yes)
			(effects
				(font
					(size 1.016 1.016)
					(thickness 0.1524)
				)
			)
		)
		(duplicate_pad_numbers_are_jumpers no)
		(fp_line
			(start -1.651 -1.778)
			(end -1.651 1.778)
			(stroke
				(width 0.1524)
				(type default)
			)
			(layer "F.SilkS")
		)
		(fp_line
			(start -1.651 1.778)
			(end 1.651 1.778)
			(stroke
				(width 0.1524)
				(type default)
			)
			(layer "F.SilkS")
		)
		(fp_line
			(start 1.651 -1.778)
			(end -1.651 -1.778)
			(stroke
				(width 0.1524)
				(type default)
			)
			(layer "F.SilkS")
		)
		(fp_line
			(start 1.651 1.778)
			(end 1.651 -1.778)
			(stroke
				(width 0.1524)
				(type default)
			)
			(layer "F.SilkS")
		)
		(fp_poly
			(pts
				(xy -1.778 1.8796) (xy -1.778 -1.8796) (xy 1.778 -1.8796) (xy 1.778 1.8796)
			)
			(stroke
				(width 0)
				(type default)
			)
			(fill no)
			(layer "F.CrtYd")
		)
		(fp_poly
			(pts
				(xy -1.778 1.8796) (xy -1.778 -1.8796) (xy 1.778 -1.8796) (xy 1.778 1.8796)
			)
			(stroke
				(width 0)
				(type default)
			)
			(fill no)
			(layer "F.Fab")
		)
		(pad "D" smd custom
			(at 0 -0.9525)
			(size 0.1905 0.1905)
			(layers "F.Cu" "F.Mask" "F.Paste")
			(net "HDD11_LED_G")
			(options
				(clearance outline)
				(anchor circle)
			)
			(primitives
				(gr_poly
					(pts
						(arc
							(start -0.1778 0.5715)
							(mid -0.321484 0.511984)
							(end -0.381 0.3683)
						)
						(arc
							(start -0.381 -0.3683)
							(mid -0.321484 -0.511984)
							(end -0.1778 -0.5715)
						)
						(arc
							(start 0.1778 -0.5715)
							(mid 0.321484 -0.511984)
							(end 0.381 -0.3683)
						)
						(arc
							(start 0.381 0.3683)
							(mid 0.321484 0.511984)
							(end 0.1778 0.5715)
						)
					)
					(width 0)
					(fill yes)
				)
			)
		)
		(pad "G" smd custom
			(at -0.98425 0.9525)
			(size 0.1905 0.1905)
			(layers "F.Cu" "F.Mask" "F.Paste")
			(net "HDD11_LED_B")
			(options
				(clearance outline)
				(anchor circle)
			)
			(primitives
				(gr_poly
					(pts
						(arc
							(start -0.1778 0.5715)
							(mid -0.321484 0.511984)
							(end -0.381 0.3683)
						)
						(arc
							(start -0.381 -0.3683)
							(mid -0.321484 -0.511984)
							(end -0.1778 -0.5715)
						)
						(arc
							(start 0.1778 -0.5715)
							(mid 0.321484 -0.511984)
							(end 0.381 -0.3683)
						)
						(arc
							(start 0.381 0.3683)
							(mid 0.321484 0.511984)
							(end 0.1778 0.5715)
						)
					)
					(width 0)
					(fill yes)
				)
			)
		)
		(pad "S" smd custom
			(at 0.98425 0.9525)
			(size 0.1905 0.1905)
			(layers "F.Cu" "F.Mask" "F.Paste")
			(net "GND")
			(options
				(clearance outline)
				(anchor circle)
			)
			(primitives
				(gr_poly
					(pts
						(arc
							(start -0.1778 0.5715)
							(mid -0.321484 0.511984)
							(end -0.381 0.3683)
						)
						(arc
							(start -0.381 -0.3683)
							(mid -0.321484 -0.511984)
							(end -0.1778 -0.5715)
						)
						(arc
							(start 0.1778 -0.5715)
							(mid 0.321484 -0.511984)
							(end 0.381 -0.3683)
						)
						(arc
							(start 0.381 0.3683)
							(mid 0.321484 0.511984)
							(end 0.1778 0.5715)
						)
					)
					(width 0)
					(fill yes)
				)
			)
		)
	)
	(footprint ""
		(layer "F.Cu")
		(at 242.061746 -25.7937 90)
		(property "Reference" "PC6"
			(at 0 0 90)
			(layer "F.SilkS")
			(hide yes)
			(effects
				(font
					(size 1.27 1.27)
				)
			)
		)
		(property "Value" "SC4D7U25V5KX-GP"
			(at -0.0762 -6.1214 90)
			(unlocked yes)
			(layer "F.Fab")
			(hide yes)
			(effects
				(font
					(size 1.016 1.016)
					(thickness 0.1524)
				)
			)
		)
		(property "Device Type" "C805H54"
			(at -0.0762 -8.1534 90)
			(unlocked yes)
			(layer "F.Fab")
			(hide yes)
			(effects
				(font
					(size 1.016 1.016)
					(thickness 0.1524)
				)
			)
		)
		(duplicate_pad_numbers_are_jumpers no)
		(fp_line
			(start 0.635 0)
			(end -0.635 0)
			(stroke
				(width 0.508)
				(type default)
			)
			(layer "F.SilkS")
		)
		(fp_rect
			(start -0.9652 1.778)
			(end 0.9652 -1.778)
			(stroke
				(width 0)
				(type default)
			)
			(fill no)
			(layer "F.CrtYd")
		)
		(fp_poly
			(pts
				(xy -0.9652 -1.778) (xy 0.9652 -1.778) (xy 0.9652 1.778) (xy -0.9652 1.778)
			)
			(stroke
				(width 0)
				(type default)
			)
			(fill no)
			(layer "F.Fab")
		)
		(pad "1" smd rect
			(at 0 -0.9652 90)
			(size 1.397 1.143)
			(layers "F.Cu" "F.Mask" "F.Paste")
			(net "P5VA_VDD")
		)
		(pad "2" smd rect
			(at 0 0.9652 90)
			(size 1.397 1.143)
			(layers "F.Cu" "F.Mask" "F.Paste")
			(net "GND")
		)
	)
	(footprint ""
		(layer "F.Cu")
		(at 59.007756 -481.485702)
		(property "Reference" "C190"
			(at 0 0 0)
			(layer "F.SilkS")
			(hide yes)
			(effects
				(font
					(size 1.27 1.27)
				)
			)
		)
		(property "Value" "SCD01U50V2KX-1GP"
			(at 1.1811 -2.7051 0)
			(unlocked yes)
			(layer "F.Fab")
			(hide yes)
			(effects
				(font
					(size 1.016 1.016)
					(thickness 0.1524)
				)
			)
		)
		(property "Device Type" "C402H22"
			(at 1.1811 -4.2291 0)
			(unlocked yes)
			(layer "F.Fab")
			(hide yes)
			(effects
				(font
					(size 1.016 1.016)
					(thickness 0.1524)
				)
			)
		)
		(duplicate_pad_numbers_are_jumpers no)
		(fp_rect
			(start -0.4318 0.9525)
			(end 0.4318 -0.9525)
			(stroke
				(width 0)
				(type default)
			)
			(fill no)
			(layer "F.CrtYd")
		)
		(fp_rect
			(start -0.4318 0.9525)
			(end 0.4318 -0.9525)
			(stroke
				(width 0)
				(type default)
			)
			(fill no)
			(layer "F.Fab")
		)
		(pad "1" smd custom
			(at 0 -0.4445)
			(size 0.1524 0.1524)
			(layers "F.Cu" "F.Mask" "F.Paste")
			(net "HDD_PRSNT_NET5")
			(options
				(clearance outline)
				(anchor circle)
			)
			(primitives
				(gr_poly
					(pts
						(arc
							(start 0.3048 -0.2032)
							(mid 0.275042 -0.275042)
							(end 0.2032 -0.3048)
						)
						(arc
							(start -0.2032 -0.3048)
							(mid -0.275042 -0.275042)
							(end -0.3048 -0.2032)
						)
						(arc
							(start -0.3048 0.2032)
							(mid -0.275042 0.275042)
							(end -0.2032 0.3048)
						)
						(arc
							(start 0.2032 0.3048)
							(mid 0.275042 0.275042)
							(end 0.3048 0.2032)
						)
					)
					(width 0)
					(fill yes)
				)
			)
		)
		(pad "2" smd custom
			(at 0 0.4445)
			(size 0.1524 0.1524)
			(layers "F.Cu" "F.Mask" "F.Paste")
			(net "GND")
			(options
				(clearance outline)
				(anchor circle)
			)
			(primitives
				(gr_poly
					(pts
						(arc
							(start 0.3048 -0.2032)
							(mid 0.275042 -0.275042)
							(end 0.2032 -0.3048)
						)
						(arc
							(start -0.2032 -0.3048)
							(mid -0.275042 -0.275042)
							(end -0.3048 -0.2032)
						)
						(arc
							(start -0.3048 0.2032)
							(mid -0.275042 0.275042)
							(end -0.2032 0.3048)
						)
						(arc
							(start 0.2032 0.3048)
							(mid 0.275042 0.275042)
							(end 0.3048 0.2032)
						)
					)
					(width 0)
					(fill yes)
				)
			)
		)
	)
	(footprint ""
		(layer "F.Cu")
		(at 30.860746 -344.4367 90)
		(property "Reference" "R254"
			(at 0 0 90)
			(layer "F.SilkS")
			(hide yes)
			(effects
				(font
					(size 1.27 1.27)
				)
			)
		)
		(property "Value" "10KR2F-2-GP"
			(at 0.064008 -3.993896 90)
			(unlocked yes)
			(layer "F.Fab")
			(hide yes)
			(effects
				(font
					(size 1.016 1.016)
					(thickness 0.1524)
				)
			)
		)
		(property "Device Type" "R402H16"
			(at 0.064008 -5.517896 90)
			(unlocked yes)
			(layer "F.Fab")
			(hide yes)
			(effects
				(font
					(size 1.016 1.016)
					(thickness 0.1524)
				)
			)
		)
		(duplicate_pad_numbers_are_jumpers no)
		(fp_line
			(start 0.508 -0.9398)
			(end -0.508 -0.9398)
			(stroke
				(width 0.1524)
				(type default)
			)
			(layer "F.SilkS")
		)
		(fp_line
			(start -0.508 -0.9398)
			(end -0.508 0.9398)
			(stroke
				(width 0.1524)
				(type default)
			)
			(layer "F.SilkS")
		)
		(fp_rect
			(start -0.508 0.9398)
			(end 0.508 -0.9398)
			(stroke
				(width 0)
				(type default)
			)
			(fill no)
			(layer "F.CrtYd")
		)
		(fp_rect
			(start -0.508 0.9398)
			(end 0.508 -0.9398)
			(stroke
				(width 0)
				(type default)
			)
			(fill no)
			(layer "F.Fab")
		)
		(pad "1" smd custom
			(at 0 -0.4445 90)
			(size 0.1397 0.1397)
			(layers "F.Cu" "F.Mask" "F.Paste")
			(net "P5VC")
			(options
				(clearance outline)
				(anchor circle)
			)
			(primitives
				(gr_poly
					(pts
						(arc
							(start -0.1778 -0.2794)
							(mid -0.249642 -0.249642)
							(end -0.2794 -0.1778)
						)
						(arc
							(start -0.2794 0.1778)
							(mid -0.249642 0.249642)
							(end -0.1778 0.2794)
						)
						(arc
							(start 0.1778 0.2794)
							(mid 0.249642 0.249642)
							(end 0.2794 0.1778)
						)
						(arc
							(start 0.2794 -0.1778)
							(mid 0.249642 -0.249642)
							(end 0.1778 -0.2794)
						)
					)
					(width 0)
					(fill yes)
				)
			)
		)
		(pad "2" smd custom
			(at 0 0.4445 90)
			(size 0.1397 0.1397)
			(layers "F.Cu" "F.Mask" "F.Paste")
			(net "DRIVE_ACT_11")
			(options
				(clearance outline)
				(anchor circle)
			)
			(primitives
				(gr_poly
					(pts
						(arc
							(start -0.1778 -0.2794)
							(mid -0.249642 -0.249642)
							(end -0.2794 -0.1778)
						)
						(arc
							(start -0.2794 0.1778)
							(mid -0.249642 0.249642)
							(end -0.1778 0.2794)
						)
						(arc
							(start 0.1778 0.2794)
							(mid 0.249642 0.249642)
							(end 0.2794 0.1778)
						)
						(arc
							(start 0.2794 -0.1778)
							(mid 0.249642 -0.249642)
							(end 0.1778 -0.2794)
						)
					)
					(width 0)
					(fill yes)
				)
			)
		)
	)
	(footprint ""
		(layer "F.Cu")
		(at 89.788746 -24.5237)
		(property "Reference" "Q29"
			(at 0 0 0)
			(layer "F.SilkS")
			(hide yes)
			(effects
				(font
					(size 1.27 1.27)
				)
			)
		)
		(property "Value" "AO4406AL-GP"
			(at -3.707384 -1.5367 0)
			(unlocked yes)
			(layer "F.Fab")
			(hide yes)
			(effects
				(font
					(size 1.016 1.016)
					(thickness 0.1524)
				)
			)
		)
		(property "Device Type" "SOIC8H69"
			(at -3.707384 -3.0607 0)
			(unlocked yes)
			(layer "F.Fab")
			(hide yes)
			(effects
				(font
					(size 1.016 1.016)
					(thickness 0.1524)
				)
			)
		)
		(duplicate_pad_numbers_are_jumpers no)
		(fp_line
			(start -2.7432 -1.4224)
			(end -2.7432 1.4224)
			(stroke
				(width 0.1524)
				(type default)
			)
			(layer "F.SilkS")
		)
		(fp_line
			(start -2.7432 1.4224)
			(end -2.6416 1.4224)
			(stroke
				(width 0.1524)
				(type default)
			)
			(layer "F.SilkS")
		)
		(fp_line
			(start -2.7432 1.4224)
			(end 2.1336 1.4224)
			(stroke
				(width 0.1524)
				(type default)
			)
			(layer "F.SilkS")
		)
		(fp_line
			(start -2.7178 -0.508)
			(end -2.1844 -0.0508)
			(stroke
				(width 0.1524)
				(type default)
			)
			(layer "F.SilkS")
		)
		(fp_line
			(start -2.6289 3.4417)
			(end -2.6289 1.4732)
			(stroke
				(width 0.381)
				(type default)
			)
			(layer "F.SilkS")
		)
		(fp_line
			(start -2.1844 -0.0508)
			(end -2.7178 0.508)
			(stroke
				(width 0.1524)
				(type default)
			)
			(layer "F.SilkS")
		)
		(fp_line
			(start 2.1336 -1.4224)
			(end -2.7432 -1.4224)
			(stroke
				(width 0.1524)
				(type default)
			)
			(layer "F.SilkS")
		)
		(fp_line
			(start 2.1336 1.4224)
			(end 2.1336 -1.4224)
			(stroke
				(width 0.1524)
				(type default)
			)
			(layer "F.SilkS")
		)
		(fp_poly
			(pts
				(xy -2.2098 -1.4224) (xy -2.2098 1.4224) (xy 2.2098 1.4224) (xy 2.2098 -1.4224)
			)
			(stroke
				(width 0)
				(type default)
			)
			(fill yes)
			(layer "F.SilkS")
		)
		(fp_rect
			(start -2.450084 2.999994)
			(end 2.450084 -2.999994)
			(stroke
				(width 0)
				(type default)
			)
			(fill no)
			(layer "F.CrtYd")
		)
		(fp_poly
			(pts
				(xy -2.8194 3.6322) (xy -2.8194 -3.6322) (xy 2.8194 -3.6322) (xy 2.8194 1.18364) (xy 2.450084 1.18364)
				(xy 2.450084 -2.999994) (xy -2.450084 -2.999994) (xy -2.450084 2.999994) (xy 2.450084 2.999994)
				(xy 2.450084 1.18618) (xy 2.8194 1.18618) (xy 2.8194 3.6322)
			)
			(stroke
				(width 0)
				(type default)
			)
			(fill no)
			(layer "F.CrtYd")
		)
		(fp_rect
			(start -2.8194 3.6322)
			(end 2.8194 -3.6322)
			(stroke
				(width 0)
				(type default)
			)
			(fill no)
			(layer "F.Fab")
		)
		(pad "1" smd rect
			(at -1.905 2.54)
			(size 0.635 1.651)
			(layers "F.Cu" "F.Mask" "F.Paste")
			(net "P5V_HDD14")
		)
		(pad "2" smd rect
			(at -0.635 2.54)
			(size 0.635 1.651)
			(layers "F.Cu" "F.Mask" "F.Paste")
			(net "P5V_HDD14")
		)
		(pad "3" smd rect
			(at 0.635 2.54)
			(size 0.635 1.651)
			(layers "F.Cu" "F.Mask" "F.Paste")
			(net "P5V_HDD14")
		)
		(pad "4" smd rect
			(at 1.905 2.54)
			(size 0.635 1.651)
			(layers "F.Cu" "F.Mask" "F.Paste")
			(net "SW_HDD14_P")
		)
		(pad "5" smd rect
			(at 1.905 -2.54)
			(size 0.635 1.651)
			(layers "F.Cu" "F.Mask" "F.Paste")
			(net "P5VC")
		)
		(pad "6" smd rect
			(at 0.635 -2.54)
			(size 0.635 1.651)
			(layers "F.Cu" "F.Mask" "F.Paste")
			(net "P5VC")
		)
		(pad "7" smd rect
			(at -0.635 -2.54)
			(size 0.635 1.651)
			(layers "F.Cu" "F.Mask" "F.Paste")
			(net "P5VC")
		)
		(pad "8" smd rect
			(at -1.905 -2.54)
			(size 0.635 1.651)
			(layers "F.Cu" "F.Mask" "F.Paste")
			(net "P5VC")
		)
	)
)
